# BASEBOARD_FAB2 (Tioga Pass) — schematic netlist excerpt (pin names and nets, part order shuffled) for the footprints in the layout excerpt that follows; sources: Cadence DE-HDL packaged netlist, KiCad conversion of Wiwynn_Tioga_Pass_MB.brd

EU9F2  RT9059  IC  pkg DFN  page 239
  VOUT(0)  = P1V2_AUX_BMC
  VOUT(1)  = P1V2_AUX_BMC
  VOUT(2)  = P1V2_AUX_BMC
  ADJ_NC  = VR_P1V2_BMC_STBY_FB
  PGOOD  = PWRGD_P1V2_BMC_STBY_R
  EN  = PWRGD_P2V5_BMC_STBY
  VIN(0)  = P3V3_STBY
  VIN(1)  = P3V3_STBY
  VIN(2)  = P3V3_STBY
  VDD  = P3V3_STBY
  GND  = GND

R8F2  RES  0.0 5% CHIP  pkg 0402  page 240 : A = PWRGD_P5V_STBY ; B = VR_P3V3_STBY_EN

(kicad_pcb
	(version 20260206)
	(generator "pcbnew")
	(generator_version "10.0")
	(general
		(thickness 1.6)
		(legacy_teardrops no)
	)
	(paper "A4")
	(title_block
		(title "Wiwynn_Tioga_Pass_MB.brd")
		(comment 1 "Tioga Pass / footprints 2296-2297 of 4770")
	)
	(layers
		(0 "F.Cu" signal "TOP")
		(4 "In1.Cu" signal "L2GND")
		(6 "In2.Cu" signal "L3")
		(8 "In3.Cu" signal "L4GND")
		(10 "In4.Cu" signal "L5")
		(12 "In5.Cu" signal "L6GND")
		(14 "In6.Cu" signal "L7VCC")
		(16 "In7.Cu" signal "L8VCC")
		(18 "In8.Cu" signal "L9GND")
		(20 "In9.Cu" signal "L10")
		(22 "In10.Cu" signal "L11GND")
		(24 "In11.Cu" signal "L12")
		(26 "In12.Cu" signal "L13GND")
		(2 "B.Cu" signal "BOTTOM")
		(9 "F.Adhes" user "F.Adhesive")
		(11 "B.Adhes" user "B.Adhesive")
		(13 "F.Paste" user "Package Geometry/Pastemask Top")
		(15 "B.Paste" user "Package Geometry/Pastemask Bottom")
		(5 "F.SilkS" user "Ref Des/Silkscreen Top")
		(7 "B.SilkS" user "Ref Des/Silkscreen Bottom")
		(1 "F.Mask" user "Board Geometry/Soldermask Top")
		(3 "B.Mask" user "Board Geometry/Soldermask Bottom")
		(17 "Dwgs.User" user "User.Drawings")
		(19 "Cmts.User" user "User.Comments")
		(21 "Eco1.User" user "User.Eco1")
		(23 "Eco2.User" user "User.Eco2")
		(25 "Edge.Cuts" user "Board Geometry/Outline")
		(27 "Margin" user)
		(31 "F.CrtYd" user "Package Geometry/Place Bound Top")
		(29 "B.CrtYd" user "Package Geometry/Place Bound Bottom")
		(35 "F.Fab" user "Ref Des/Assembly Top")
		(33 "B.Fab" user "Ref Des/Assembly Bottom")
	)
	(footprint ""
		(layer "F.Cu")
		(at 469.077802 -38.188392 90)
		(property "Reference" "EU9F2"
			(at -0.6096 -1.21793 90)
			(unlocked yes)
			(layer "F.SilkS")
			(effects
				(font
					(size 0.7874 0.5842)
					(thickness 0.1524)
				)
				(justify left)
			)
		)
		(property "Value" ""
			(at 0 0 90)
			(layer "F.Fab")
			(effects
				(font
					(size 1.27 1.27)
				)
			)
		)
		(duplicate_pad_numbers_are_jumpers no)
		(fp_circle
			(center -0.570484 -0.440944)
			(end -0.570484 -0.314198)
			(stroke
				(width 0.254)
				(type default)
			)
			(fill no)
			(layer "F.SilkS")
		)
		(fp_poly
			(pts
				(xy -0.064516 -1.0922) (xy -0.064516 -0.3302) (xy 0.697484 -1.0922)
			)
			(stroke
				(width 0)
				(type default)
			)
			(fill yes)
			(layer "F.SilkS")
		)
		(fp_rect
			(start 0.597408 2.295398)
			(end 2.273808 -0.295402)
			(stroke
				(width 0)
				(type default)
			)
			(fill yes)
			(layer "F.Paste")
		)
		(fp_rect
			(start -0.064516 2.500122)
			(end 2.935478 -0.500126)
			(stroke
				(width 0)
				(type default)
			)
			(fill no)
			(layer "F.CrtYd")
		)
		(fp_line
			(start 2.935478 -0.500126)
			(end 2.935478 2.500122)
			(stroke
				(width 0.1)
				(type default)
			)
			(layer "F.Fab")
		)
		(fp_line
			(start -0.064516 -0.500126)
			(end 2.935478 -0.500126)
			(stroke
				(width 0.1)
				(type default)
			)
			(layer "F.Fab")
		)
		(fp_line
			(start 2.935478 2.500122)
			(end -0.064516 2.500122)
			(stroke
				(width 0.1)
				(type default)
			)
			(layer "F.Fab")
		)
		(fp_line
			(start -0.064516 2.500122)
			(end -0.064516 -0.500126)
			(stroke
				(width 0.1)
				(type default)
			)
			(layer "F.Fab")
		)
		(fp_circle
			(center -0.835152 -0.417322)
			(end -0.835152 -0.290576)
			(stroke
				(width 0.254)
				(type default)
			)
			(fill no)
			(layer "F.Fab")
		)
		(pad "1" smd rect
			(at 0 0 90)
			(size 0.6858 0.3048)
			(layers "F.Cu" "F.Mask" "F.Paste")
			(net "P1V2_AUX_BMC")
		)
		(pad "2" smd rect
			(at 0 0.500126 90)
			(size 0.6858 0.3048)
			(layers "F.Cu" "F.Mask" "F.Paste")
			(net "P1V2_AUX_BMC")
		)
		(pad "3" smd rect
			(at 0 0.999998 90)
			(size 0.6858 0.3048)
			(layers "F.Cu" "F.Mask" "F.Paste")
			(net "P1V2_AUX_BMC")
		)
		(pad "4" smd rect
			(at 0 1.500124 90)
			(size 0.6858 0.3048)
			(layers "F.Cu" "F.Mask" "F.Paste")
			(net "VR_P1V2_BMC_STBY_FB")
		)
		(pad "5" smd rect
			(at 0 1.999996 90)
			(size 0.6858 0.3048)
			(layers "F.Cu" "F.Mask" "F.Paste")
			(net "PWRGD_P1V2_BMC_STBY_R")
		)
		(pad "6" smd rect
			(at 2.871216 1.999996 90)
			(size 0.6858 0.3048)
			(layers "F.Cu" "F.Mask" "F.Paste")
			(net "PWRGD_P2V5_BMC_STBY")
		)
		(pad "7" smd rect
			(at 2.871216 1.500124 90)
			(size 0.6858 0.3048)
			(layers "F.Cu" "F.Mask" "F.Paste")
			(net "P3V3_STBY")
		)
		(pad "8" smd rect
			(at 2.871216 0.999998 90)
			(size 0.6858 0.3048)
			(layers "F.Cu" "F.Mask" "F.Paste")
			(net "P3V3_STBY")
		)
		(pad "9" smd rect
			(at 2.871216 0.500126 90)
			(size 0.6858 0.3048)
			(layers "F.Cu" "F.Mask" "F.Paste")
			(net "P3V3_STBY")
		)
		(pad "10" smd rect
			(at 2.871216 0 90)
			(size 0.6858 0.3048)
			(layers "F.Cu" "F.Mask" "F.Paste")
			(net "P3V3_STBY")
		)
		(pad "11" smd rect
			(at 1.435608 0.999998 90)
			(size 1.6764 2.5908)
			(layers "F.Cu" "F.Mask" "F.Paste")
			(net "GND")
		)
	)
	(footprint ""
		(layer "F.Cu")
		(at 464.7057 -23.0759 90)
		(property "Reference" "R8F2"
			(at 0 0 90)
			(layer "F.SilkS")
			(hide yes)
			(effects
				(font
					(size 1.27 1.27)
				)
			)
		)
		(property "Value" ""
			(at 0 0 90)
			(layer "F.Fab")
			(effects
				(font
					(size 1.27 1.27)
				)
			)
		)
		(duplicate_pad_numbers_are_jumpers no)
		(fp_poly
			(pts
				(xy -0.2794 -0.1016) (xy 0.2794 -0.1016) (xy 0.2794 0.9906) (xy -0.2794 0.9906)
			)
			(stroke
				(width 0)
				(type default)
			)
			(fill no)
			(layer "F.CrtYd")
		)
		(fp_line
			(start 0.2794 -0.1016)
			(end -0.2794 -0.1016)
			(stroke
				(width 0.1)
				(type default)
			)
			(layer "F.Fab")
		)
		(fp_line
			(start -0.2794 -0.1016)
			(end -0.2794 0.9906)
			(stroke
				(width 0.1)
				(type default)
			)
			(layer "F.Fab")
		)
		(fp_line
			(start 0.2794 0.9906)
			(end 0.2794 -0.1016)
			(stroke
				(width 0.1)
				(type default)
			)
			(layer "F.Fab")
		)
		(fp_line
			(start -0.2794 0.9906)
			(end 0.2794 0.9906)
			(stroke
				(width 0.1)
				(type default)
			)
			(layer "F.Fab")
		)
		(pad "1" smd rect
			(at 0 0 90)
			(size 0.508 0.508)
			(layers "F.Cu" "F.Mask" "F.Paste")
			(net "PWRGD_P5V_STBY")
		)
		(pad "2" smd rect
			(at 0 0.889 90)
			(size 0.508 0.508)
			(layers "F.Cu" "F.Mask" "F.Paste")
			(net "VR_P3V3_STBY_EN")
		)
		(zone
			(layer "F.Cu")
			(hatch none 0.5)
			(connect_pads
				(clearance 0)
			)
			(min_thickness 0.25)
			(keepout
				(tracks allowed)
				(vias not_allowed)
				(pads allowed)
				(copperpour not_allowed)
				(footprints allowed)
			)
			(placement
				(enabled no)
				(sheetname "")
			)
			(fill
				(thermal_gap 0.5)
				(thermal_bridge_width 0.5)
				(island_removal_mode 0)
			)
			(polygon
				(pts
					(xy 464.9597 -22.8219) (xy 464.9597 -23.3299) (xy 465.3407 -23.3299) (xy 465.3407 -22.8219)
				)
			)
		)
		(zone
			(layer "F.Cu")
			(hatch none 0.5)
			(connect_pads
				(clearance 0)
			)
			(min_thickness 0.25)
			(keepout
				(tracks not_allowed)
				(vias allowed)
				(pads allowed)
				(copperpour not_allowed)
				(footprints allowed)
			)
			(placement
				(enabled no)
				(sheetname "")
			)
			(fill
				(thermal_gap 0.5)
				(thermal_bridge_width 0.5)
				(island_removal_mode 0)
			)
			(polygon
				(pts
					(xy 465.3407 -22.8219) (xy 465.3407 -23.3299) (xy 464.9597 -23.3299) (xy 464.9597 -22.8219)
				)
			)
		)
	)
)
